# S9S_MB_2U (Grand Teton) — schematic netlist excerpt (pin names and nets, part order shuffled) for the footprints in the layout excerpt that follows; sources: Cadence DE-HDL packaged netlist, KiCad conversion of 03242023_DA0F0TMBIJ0_F0T_Motherboard_J_brd_V01_OCP.brd

PC445_P1_2  Q_CAP  1UF 16V 10% X6S  pkg C0402  page 293 : A = SW_P12V_PVCCINFAON_CPU1_FLT ; B = GND
PC227  Q_CAP  2.2UF 10V 10% X6S  pkg C0402  page 270 : A = PVCCIN_CPU0_VDD7 ; B = GND
C903  Q_CAP_DIFFBUS  DIFF BUS_0.22UF 6.3V 20% X6S  pkg C0201  page 173 : \1\ = P5E_CPU0_PE0_TX_C_DP<15> ; \2\ = P5E_CPU0_PE0_TX_DP<15>

(kicad_pcb
	(version 20260206)
	(generator "pcbnew")
	(generator_version "10.0")
	(general
		(thickness 1.6)
		(legacy_teardrops no)
	)
	(paper "A4")
	(title_block
		(title "03242023_DA0F0TMBIJ0_F0T_Motherboard_J_brd_V01_OCP.brd")
		(comment 1 "Grand Teton / footprints 3621-3623 of 6105")
	)
	(layers
		(0 "F.Cu" signal "TOP")
		(4 "In1.Cu" signal "GND")
		(6 "In2.Cu" signal "IN1")
		(8 "In3.Cu" signal "GND1")
		(10 "In4.Cu" signal "IN2")
		(12 "In5.Cu" signal "GND2")
		(14 "In6.Cu" signal "IN3")
		(16 "In7.Cu" signal "GND3")
		(18 "In8.Cu" signal "VCC")
		(20 "In9.Cu" signal "VCC1")
		(22 "In10.Cu" signal "GND4")
		(24 "In11.Cu" signal "IN4")
		(26 "In12.Cu" signal "GND5")
		(28 "In13.Cu" signal "IN5")
		(30 "In14.Cu" signal "GND6")
		(32 "In15.Cu" signal "IN6")
		(34 "In16.Cu" signal "GND7")
		(2 "B.Cu" signal "BOTTOM")
		(9 "F.Adhes" user "F.Adhesive")
		(11 "B.Adhes" user "B.Adhesive")
		(13 "F.Paste" user "Package Geometry/Pastemask Top")
		(15 "B.Paste" user "Package Geometry/Pastemask Bottom")
		(5 "F.SilkS" user "Ref Des/Silkscreen Top")
		(7 "B.SilkS" user "Ref Des/Silkscreen Bottom")
		(1 "F.Mask" user "Board Geometry/Soldermask Top")
		(3 "B.Mask" user "Board Geometry/Soldermask Bottom")
		(17 "Dwgs.User" user "User.Drawings")
		(19 "Cmts.User" user "User.Comments")
		(21 "Eco1.User" user "User.Eco1")
		(23 "Eco2.User" user "User.Eco2")
		(25 "Edge.Cuts" user "Board Geometry/Outline")
		(27 "Margin" user)
		(31 "F.CrtYd" user "Package Geometry/Place Bound Top")
		(29 "B.CrtYd" user "Package Geometry/Place Bound Bottom")
		(35 "F.Fab" user "Ref Des/Assembly Top")
		(33 "B.Fab" user "Ref Des/Assembly Bottom")
	)
	(footprint ""
		(layer "F.Cu")
		(at 54.811168 -151.411178)
		(property "Reference" "PC445_P1_2"
			(at 0 0 0)
			(layer "F.SilkS")
			(hide yes)
			(effects
				(font
					(size 1.27 1.27)
				)
			)
		)
		(property "Value" ""
			(at 0 0 0)
			(layer "F.Fab")
			(effects
				(font
					(size 1.27 1.27)
				)
			)
		)
		(duplicate_pad_numbers_are_jumpers no)
		(fp_line
			(start -0.7874 -0.4064)
			(end 0.7874 -0.4064)
			(stroke
				(width 0.1524)
				(type default)
			)
			(layer "F.SilkS")
		)
		(fp_line
			(start -0.7874 0.4064)
			(end -0.7874 -0.4064)
			(stroke
				(width 0.1524)
				(type default)
			)
			(layer "F.SilkS")
		)
		(fp_line
			(start 0.7874 -0.4064)
			(end 0.7874 0.4064)
			(stroke
				(width 0.1524)
				(type default)
			)
			(layer "F.SilkS")
		)
		(fp_line
			(start 0.7874 0.4064)
			(end -0.7874 0.4064)
			(stroke
				(width 0.1524)
				(type default)
			)
			(layer "F.SilkS")
		)
		(fp_line
			(start -0.67945 -0.305054)
			(end -0.12065 -0.305054)
			(stroke
				(width 0.1)
				(type default)
			)
			(layer "F.Fab")
		)
		(fp_line
			(start -0.67945 0.3048)
			(end -0.67945 -0.305054)
			(stroke
				(width 0.1)
				(type default)
			)
			(layer "F.Fab")
		)
		(fp_line
			(start -0.12065 -0.305054)
			(end -0.12065 -0.2794)
			(stroke
				(width 0.1)
				(type default)
			)
			(layer "F.Fab")
		)
		(fp_line
			(start -0.12065 -0.2794)
			(end 0.12065 -0.2794)
			(stroke
				(width 0.1)
				(type default)
			)
			(layer "F.Fab")
		)
		(fp_line
			(start -0.12065 0.2794)
			(end -0.12065 0.3048)
			(stroke
				(width 0.1)
				(type default)
			)
			(layer "F.Fab")
		)
		(fp_line
			(start -0.12065 0.3048)
			(end -0.67945 0.3048)
			(stroke
				(width 0.1)
				(type default)
			)
			(layer "F.Fab")
		)
		(fp_line
			(start 0.120396 0.2794)
			(end -0.12065 0.2794)
			(stroke
				(width 0.1)
				(type default)
			)
			(layer "F.Fab")
		)
		(fp_line
			(start 0.120396 0.3048)
			(end 0.120396 0.2794)
			(stroke
				(width 0.1)
				(type default)
			)
			(layer "F.Fab")
		)
		(fp_line
			(start 0.12065 -0.3048)
			(end 0.67945 -0.3048)
			(stroke
				(width 0.1)
				(type default)
			)
			(layer "F.Fab")
		)
		(fp_line
			(start 0.12065 -0.2794)
			(end 0.12065 -0.3048)
			(stroke
				(width 0.1)
				(type default)
			)
			(layer "F.Fab")
		)
		(fp_line
			(start 0.67945 -0.3048)
			(end 0.67945 0.3048)
			(stroke
				(width 0.1)
				(type default)
			)
			(layer "F.Fab")
		)
		(fp_line
			(start 0.67945 0.3048)
			(end 0.120396 0.3048)
			(stroke
				(width 0.1)
				(type default)
			)
			(layer "F.Fab")
		)
		(pad "1" smd circle
			(at -0.40005 0)
			(size 0 0)
			(layers "F.Cu" "F.Mask" "F.Paste")
			(net "SW_P12V_PVCCINFAON_CPU1_FLT")
		)
		(pad "2" smd circle
			(at 0.40005 0)
			(size 0 0)
			(layers "F.Cu" "F.Mask" "F.Paste")
			(net "GND")
		)
	)
	(footprint ""
		(layer "F.Cu")
		(at 306.215288 -408.517344 -90)
		(property "Reference" "C903"
			(at 0 0 270)
			(layer "F.SilkS")
			(hide yes)
			(effects
				(font
					(size 1.27 1.27)
				)
			)
		)
		(property "Value" ""
			(at 0 0 270)
			(layer "F.Fab")
			(effects
				(font
					(size 1.27 1.27)
				)
			)
		)
		(duplicate_pad_numbers_are_jumpers no)
		(fp_line
			(start -0.299974 0.150114)
			(end -0.299974 -0.150114)
			(stroke
				(width 0.1)
				(type default)
			)
			(layer "F.Fab")
		)
		(fp_line
			(start 0.299974 0.150114)
			(end -0.299974 0.150114)
			(stroke
				(width 0.1)
				(type default)
			)
			(layer "F.Fab")
		)
		(fp_line
			(start -0.299974 -0.150114)
			(end 0.299974 -0.150114)
			(stroke
				(width 0.1)
				(type default)
			)
			(layer "F.Fab")
		)
		(fp_line
			(start 0.299974 -0.150114)
			(end 0.299974 0.150114)
			(stroke
				(width 0.1)
				(type default)
			)
			(layer "F.Fab")
		)
		(pad "1" smd rect
			(at -0.2667 0 270)
			(size 0.3048 0.381)
			(layers "F.Cu" "F.Mask" "F.Paste")
			(net "P5E_CPU0_PE0_TX_C_DP<15>")
		)
		(pad "2" smd rect
			(at 0.2667 0 270)
			(size 0.3048 0.381)
			(layers "F.Cu" "F.Mask" "F.Paste")
			(net "P5E_CPU0_PE0_TX_DP<15>")
		)
	)
	(footprint ""
		(layer "F.Cu")
		(at 325.077836 -345.462606 90)
		(property "Reference" "PC227"
			(at 0 0 90)
			(layer "F.SilkS")
			(hide yes)
			(effects
				(font
					(size 1.27 1.27)
				)
			)
		)
		(property "Value" ""
			(at 0 0 90)
			(layer "F.Fab")
			(effects
				(font
					(size 1.27 1.27)
				)
			)
		)
		(duplicate_pad_numbers_are_jumpers no)
		(fp_line
			(start 0.7874 -0.4064)
			(end 0.7874 0.4064)
			(stroke
				(width 0.1524)
				(type default)
			)
			(layer "F.SilkS")
		)
		(fp_line
			(start -0.7874 -0.4064)
			(end 0.7874 -0.4064)
			(stroke
				(width 0.1524)
				(type default)
			)
			(layer "F.SilkS")
		)
		(fp_line
			(start 0.7874 0.4064)
			(end -0.7874 0.4064)
			(stroke
				(width 0.1524)
				(type default)
			)
			(layer "F.SilkS")
		)
		(fp_line
			(start -0.7874 0.4064)
			(end -0.7874 -0.4064)
			(stroke
				(width 0.1524)
				(type default)
			)
			(layer "F.SilkS")
		)
		(fp_line
			(start -0.12065 -0.305054)
			(end -0.12065 -0.2794)
			(stroke
				(width 0.1)
				(type default)
			)
			(layer "F.Fab")
		)
		(fp_line
			(start -0.67945 -0.305054)
			(end -0.12065 -0.305054)
			(stroke
				(width 0.1)
				(type default)
			)
			(layer "F.Fab")
		)
		(fp_line
			(start 0.67945 -0.3048)
			(end 0.67945 0.3048)
			(stroke
				(width 0.1)
				(type default)
			)
			(layer "F.Fab")
		)
		(fp_line
			(start 0.12065 -0.3048)
			(end 0.67945 -0.3048)
			(stroke
				(width 0.1)
				(type default)
			)
			(layer "F.Fab")
		)
		(fp_line
			(start 0.12065 -0.2794)
			(end 0.12065 -0.3048)
			(stroke
				(width 0.1)
				(type default)
			)
			(layer "F.Fab")
		)
		(fp_line
			(start -0.12065 -0.2794)
			(end 0.12065 -0.2794)
			(stroke
				(width 0.1)
				(type default)
			)
			(layer "F.Fab")
		)
		(fp_line
			(start 0.120396 0.2794)
			(end -0.12065 0.2794)
			(stroke
				(width 0.1)
				(type default)
			)
			(layer "F.Fab")
		)
		(fp_line
			(start -0.12065 0.2794)
			(end -0.12065 0.3048)
			(stroke
				(width 0.1)
				(type default)
			)
			(layer "F.Fab")
		)
		(fp_line
			(start 0.67945 0.3048)
			(end 0.120396 0.3048)
			(stroke
				(width 0.1)
				(type default)
			)
			(layer "F.Fab")
		)
		(fp_line
			(start 0.120396 0.3048)
			(end 0.120396 0.2794)
			(stroke
				(width 0.1)
				(type default)
			)
			(layer "F.Fab")
		)
		(fp_line
			(start -0.12065 0.3048)
			(end -0.67945 0.3048)
			(stroke
				(width 0.1)
				(type default)
			)
			(layer "F.Fab")
		)
		(fp_line
			(start -0.67945 0.3048)
			(end -0.67945 -0.305054)
			(stroke
				(width 0.1)
				(type default)
			)
			(layer "F.Fab")
		)
		(pad "1" smd circle
			(at -0.40005 0 90)
			(size 0 0)
			(layers "F.Cu" "F.Mask" "F.Paste")
			(net "PVCCIN_CPU0_VDD7")
		)
		(pad "2" smd circle
			(at 0.40005 0 90)
			(size 0 0)
			(layers "F.Cu" "F.Mask" "F.Paste")
			(net "GND")
		)
	)
)
